# S9S_MB_2U (Grand Teton) — schematic netlist excerpt (pin names and nets, part order shuffled) for the footprints in the layout excerpt that follows; sources: Cadence DE-HDL packaged netlist, KiCad conversion of 03242023_DA0F0TMBIJ0_F0T_Motherboard_J_brd_V01_OCP.brd

R4099  Q_RES  10K 1% CHIP  pkg 0402LF  page 183 : A = PD_PCH_GPPC_A_10 ; B = GND
R3827  Q_RES  0 5% EMPTY  pkg 0402LF  page 162 : A = P12V_OCP_UV_2_R ; B = P12V_OCP_UV_2

(kicad_pcb
	(version 20260206)
	(generator "pcbnew")
	(generator_version "10.0")
	(general
		(thickness 1.6)
		(legacy_teardrops no)
	)
	(paper "A4")
	(title_block
		(title "03242023_DA0F0TMBIJ0_F0T_Motherboard_J_brd_V01_OCP.brd")
		(comment 1 "Grand Teton / footprints 998-999 of 6105")
	)
	(layers
		(0 "F.Cu" signal "TOP")
		(4 "In1.Cu" signal "GND")
		(6 "In2.Cu" signal "IN1")
		(8 "In3.Cu" signal "GND1")
		(10 "In4.Cu" signal "IN2")
		(12 "In5.Cu" signal "GND2")
		(14 "In6.Cu" signal "IN3")
		(16 "In7.Cu" signal "GND3")
		(18 "In8.Cu" signal "VCC")
		(20 "In9.Cu" signal "VCC1")
		(22 "In10.Cu" signal "GND4")
		(24 "In11.Cu" signal "IN4")
		(26 "In12.Cu" signal "GND5")
		(28 "In13.Cu" signal "IN5")
		(30 "In14.Cu" signal "GND6")
		(32 "In15.Cu" signal "IN6")
		(34 "In16.Cu" signal "GND7")
		(2 "B.Cu" signal "BOTTOM")
		(9 "F.Adhes" user "F.Adhesive")
		(11 "B.Adhes" user "B.Adhesive")
		(13 "F.Paste" user "Package Geometry/Pastemask Top")
		(15 "B.Paste" user "Package Geometry/Pastemask Bottom")
		(5 "F.SilkS" user "Ref Des/Silkscreen Top")
		(7 "B.SilkS" user "Ref Des/Silkscreen Bottom")
		(1 "F.Mask" user "Board Geometry/Soldermask Top")
		(3 "B.Mask" user "Board Geometry/Soldermask Bottom")
		(17 "Dwgs.User" user "User.Drawings")
		(19 "Cmts.User" user "User.Comments")
		(21 "Eco1.User" user "User.Eco1")
		(23 "Eco2.User" user "User.Eco2")
		(25 "Edge.Cuts" user "Board Geometry/Outline")
		(27 "Margin" user)
		(31 "F.CrtYd" user "Package Geometry/Place Bound Top")
		(29 "B.CrtYd" user "Package Geometry/Place Bound Bottom")
		(35 "F.Fab" user "Ref Des/Assembly Top")
		(33 "B.Fab" user "Ref Des/Assembly Bottom")
	)
	(footprint ""
		(layer "F.Cu")
		(at 323.72808 -21.046948 -90)
		(property "Reference" "R4099"
			(at 0 0 270)
			(layer "F.SilkS")
			(hide yes)
			(effects
				(font
					(size 1.27 1.27)
				)
			)
		)
		(property "Value" ""
			(at 0 0 270)
			(layer "F.Fab")
			(effects
				(font
					(size 1.27 1.27)
				)
			)
		)
		(duplicate_pad_numbers_are_jumpers no)
		(fp_line
			(start -0.7874 0.4064)
			(end -0.7874 -0.4064)
			(stroke
				(width 0.1524)
				(type default)
			)
			(layer "F.SilkS")
		)
		(fp_line
			(start 0.7874 0.4064)
			(end -0.7874 0.4064)
			(stroke
				(width 0.1524)
				(type default)
			)
			(layer "F.SilkS")
		)
		(fp_line
			(start -0.7874 -0.4064)
			(end 0.7874 -0.4064)
			(stroke
				(width 0.1524)
				(type default)
			)
			(layer "F.SilkS")
		)
		(fp_line
			(start 0.7874 -0.4064)
			(end 0.7874 0.4064)
			(stroke
				(width 0.1524)
				(type default)
			)
			(layer "F.SilkS")
		)
		(fp_line
			(start -0.67945 0.3048)
			(end -0.67945 -0.305054)
			(stroke
				(width 0.1)
				(type default)
			)
			(layer "F.Fab")
		)
		(fp_line
			(start -0.12065 0.3048)
			(end -0.67945 0.3048)
			(stroke
				(width 0.1)
				(type default)
			)
			(layer "F.Fab")
		)
		(fp_line
			(start 0.120396 0.3048)
			(end 0.120396 0.2794)
			(stroke
				(width 0.1)
				(type default)
			)
			(layer "F.Fab")
		)
		(fp_line
			(start 0.67945 0.3048)
			(end 0.120396 0.3048)
			(stroke
				(width 0.1)
				(type default)
			)
			(layer "F.Fab")
		)
		(fp_line
			(start -0.12065 0.2794)
			(end -0.12065 0.3048)
			(stroke
				(width 0.1)
				(type default)
			)
			(layer "F.Fab")
		)
		(fp_line
			(start 0.120396 0.2794)
			(end -0.12065 0.2794)
			(stroke
				(width 0.1)
				(type default)
			)
			(layer "F.Fab")
		)
		(fp_line
			(start -0.12065 -0.2794)
			(end 0.12065 -0.2794)
			(stroke
				(width 0.1)
				(type default)
			)
			(layer "F.Fab")
		)
		(fp_line
			(start 0.12065 -0.2794)
			(end 0.12065 -0.3048)
			(stroke
				(width 0.1)
				(type default)
			)
			(layer "F.Fab")
		)
		(fp_line
			(start 0.12065 -0.3048)
			(end 0.67945 -0.3048)
			(stroke
				(width 0.1)
				(type default)
			)
			(layer "F.Fab")
		)
		(fp_line
			(start 0.67945 -0.3048)
			(end 0.67945 0.3048)
			(stroke
				(width 0.1)
				(type default)
			)
			(layer "F.Fab")
		)
		(fp_line
			(start -0.67945 -0.305054)
			(end -0.12065 -0.305054)
			(stroke
				(width 0.1)
				(type default)
			)
			(layer "F.Fab")
		)
		(fp_line
			(start -0.12065 -0.305054)
			(end -0.12065 -0.2794)
			(stroke
				(width 0.1)
				(type default)
			)
			(layer "F.Fab")
		)
		(pad "1" smd circle
			(at -0.40005 0 270)
			(size 0 0)
			(layers "F.Cu" "F.Mask" "F.Paste")
			(net "PD_PCH_GPPC_A_10")
		)
		(pad "2" smd circle
			(at 0.40005 0 270)
			(size 0 0)
			(layers "F.Cu" "F.Mask" "F.Paste")
			(net "GND")
		)
	)
	(footprint ""
		(layer "F.Cu")
		(at 66.0654 -39.487348 90)
		(property "Reference" "R3827"
			(at 0 0 90)
			(layer "F.SilkS")
			(hide yes)
			(effects
				(font
					(size 1.27 1.27)
				)
			)
		)
		(property "Value" ""
			(at 0 0 90)
			(layer "F.Fab")
			(effects
				(font
					(size 1.27 1.27)
				)
			)
		)
		(duplicate_pad_numbers_are_jumpers no)
		(fp_line
			(start 0.7874 -0.4064)
			(end 0.7874 0.4064)
			(stroke
				(width 0.1524)
				(type default)
			)
			(layer "F.SilkS")
		)
		(fp_line
			(start -0.7874 -0.4064)
			(end 0.7874 -0.4064)
			(stroke
				(width 0.1524)
				(type default)
			)
			(layer "F.SilkS")
		)
		(fp_line
			(start 0.7874 0.4064)
			(end -0.7874 0.4064)
			(stroke
				(width 0.1524)
				(type default)
			)
			(layer "F.SilkS")
		)
		(fp_line
			(start -0.7874 0.4064)
			(end -0.7874 -0.4064)
			(stroke
				(width 0.1524)
				(type default)
			)
			(layer "F.SilkS")
		)
		(fp_line
			(start -0.12065 -0.305054)
			(end -0.12065 -0.2794)
			(stroke
				(width 0.1)
				(type default)
			)
			(layer "F.Fab")
		)
		(fp_line
			(start -0.67945 -0.305054)
			(end -0.12065 -0.305054)
			(stroke
				(width 0.1)
				(type default)
			)
			(layer "F.Fab")
		)
		(fp_line
			(start 0.67945 -0.3048)
			(end 0.67945 0.3048)
			(stroke
				(width 0.1)
				(type default)
			)
			(layer "F.Fab")
		)
		(fp_line
			(start 0.12065 -0.3048)
			(end 0.67945 -0.3048)
			(stroke
				(width 0.1)
				(type default)
			)
			(layer "F.Fab")
		)
		(fp_line
			(start 0.12065 -0.2794)
			(end 0.12065 -0.3048)
			(stroke
				(width 0.1)
				(type default)
			)
			(layer "F.Fab")
		)
		(fp_line
			(start -0.12065 -0.2794)
			(end 0.12065 -0.2794)
			(stroke
				(width 0.1)
				(type default)
			)
			(layer "F.Fab")
		)
		(fp_line
			(start 0.120396 0.2794)
			(end -0.12065 0.2794)
			(stroke
				(width 0.1)
				(type default)
			)
			(layer "F.Fab")
		)
		(fp_line
			(start -0.12065 0.2794)
			(end -0.12065 0.3048)
			(stroke
				(width 0.1)
				(type default)
			)
			(layer "F.Fab")
		)
		(fp_line
			(start 0.67945 0.3048)
			(end 0.120396 0.3048)
			(stroke
				(width 0.1)
				(type default)
			)
			(layer "F.Fab")
		)
		(fp_line
			(start 0.120396 0.3048)
			(end 0.120396 0.2794)
			(stroke
				(width 0.1)
				(type default)
			)
			(layer "F.Fab")
		)
		(fp_line
			(start -0.12065 0.3048)
			(end -0.67945 0.3048)
			(stroke
				(width 0.1)
				(type default)
			)
			(layer "F.Fab")
		)
		(fp_line
			(start -0.67945 0.3048)
			(end -0.67945 -0.305054)
			(stroke
				(width 0.1)
				(type default)
			)
			(layer "F.Fab")
		)
		(pad "1" smd circle
			(at -0.40005 0 90)
			(size 0 0)
			(layers "F.Cu" "F.Mask" "F.Paste")
			(net "P12V_OCP_UV_2_R")
		)
		(pad "2" smd circle
			(at 0.40005 0 90)
			(size 0 0)
			(layers "F.Cu" "F.Mask" "F.Paste")
			(net "P12V_OCP_UV_2")
		)
	)
)
